﻿================================================================================================================
QUANTA Computer Inc. BIOS RELEASE NOTES
================================================================================================================
Project Name                : F0TG (Grand Teton Inference)
BIOS Version                : F0TG3A03
Build Date                  : 2023/06/21
Update BootBlock            : YES 
Clear NVRAM                 : YES 
BIN Checksum(16MB)          : C22C5DAB
BIN MD5 (16MB)              : 9990CAA7AD96C1B90F4301D5093AB586
BIN SHA256 Checksum (16MB)  : 822f497b4ce41babc081112ff61b56c3e5abc1c7a2faa11ff2742a10e16f33fa
TPM 2.0 SHA256 PCR 0        : 01 39 7C F6 A5 CA E5 07 42 A4 FA 2B 39 ED 28 80 83 AB E0 36 9F B4 35 21 E1 BA C2 D2 D5 72 F3 95

================================================================================================================
                             HARDWARE REQUIREMENTS/REVISIONS
================================================================================================================
System hardware revision supported: F0TG Power On CPU tray(CPU*2, DIMM*24, E1.S*1, NIC*2) + IOX(E1.S*8) + HGX(GPU*8).

================================================================================================================
                             AMD PROCESSOR MICROCODE REVISIONS
================================================================================================================
-----------------------+---------------------------------------+--------------------
Filename               | Description                           | Stepping(s)
-----------------------+---------------------------------------+--------------------
UcodePatch_RS_B0.bin   | Family 19h, Model 10h-1Fh: 0x0A101020 | Genoa B0
UcodePatch_RS_B1.bin   | Family 19h, Model 10h-1Fh: 0X0A10113B | Genoa B1
UcodePatch_RS_B2.bin   | Family 19h, Model 10h-1Fh: 0X0A10123B | Genoa B2
UcodePatch_RSDN_A0.bin | Family 19h, Model 10h-1Fh: 0x0AA00009 | Bergamo A0
UcodePatch_RSDN_A1.bin | Family 19h, Model 10h-1Fh: 0X0AA00115 | Bergamo A1
UcodePatch_RSDN_A2.bin | Family 19h, Model 10h-1Fh: 0X0AA00211 | Bergamo A2
-----------------------+---------------------------------------+--------------------
================================================================================================================
                             SYSTEM FIRMWARE REQUIREMENTS/REVISIONS
================================================================================================================
BIOS Core Version                 : 5.27
BIOS Compliancy                   : UEFI 2.8; PI 1.7
AGESA PI Version                  : 1.0.0.8
AMI BIOS Label                    : 5.27_GenoaCrb_0ACQT021
ABL                               : RABLRS10088011
PSP FW Version                    : 00.29.00.90
SMU FW Version(B0)                : 04.71.111.0
SMU FW Version(Bergamo)           : 00.91.111.0
SEV Version                       : 1.1.37.13
MPIO FW Version                   : 1.00.26.86

================================================================================================================
                             IMPORTANT INSTALLATION NOTES
================================================================================================================
I. WARNING:
  1. It is very important to follow the flash option that provided in the flash batch file
     to update the system BIOS.
     Using the incorrect flash parameters to flash BIOS may cause the damage to your system.

II. BIOS Upgrade:
  1. Burn 16MB F0TGXXXX.BIN via fixture.
  2. Please execute chmod +x for executable file.
  3. Please execute run_script, the update procedure will start automatically. 
   - After update procedure done system need to reset for new BIOS running.
        Command: "./run_script"
   - To update forcibly without platform identify, need to add "-force" in those several files:
		(1) run_script(Line: 1): ./PreUpdate.sh F0TGXXXX.BIN -force
		(2) biosupdate.sh(Line: 1): ./PreUpdate.sh $1 -force
  4. To clear NVRAM:
        Command "./afulnx_64 ROM_FILE.BIN /n".

III. Console Setting:
  1. COM port usage is default direct to ttyS1.
  2. 57600/VT100 is default console redirection setting.
  3. Linux boot configuration for serial: "console=ttyS0,57600n8".

IV. BIOS vesion and supported CPV.
  1. dTPM is required and installed on MB to Power ON.
  
V. BIOS vesion and supported CPU mapping table: (O:Support / X: Not Support)
+---------------------------------+--------+------+--------+--------------+---------------+
|Genoa/Bergamo SP5 CPU/ BIOS Ver. | ~ 1A11 | 1A12 |  1A13  |  2A01 ~ 2A03 |  2A04 ~ 3A03  |
+---------------------------------+--------+------+--------+--------------+---------------+
|Genoa A0 Stepping                |    O   |  O   |    X   |       X      |       X       |
+---------------------------------+--------+------+--------+--------------+---------------+
|Genoa A1 Stepping                |    O   |  O   |    X   |       X      |       X       |
+---------------------------------+--------+------+--------+--------------+---------------+
|Genoa B0 Stepping                |    O   |  O   |    O   |       O      |       O       |
+---------------------------------+--------+------+--------+--------------+---------------+
|Genoa B1 Stepping                |    O   |  O   |    O   |       O      |       O       |
+---------------------------------+--------+------+--------+--------------+---------------+
|Bergamo A0 Stepping              |    O   |  O   |    O   |       O      |       O       |
+---------------------------------+--------+------+--------+--------------+---------------+
|Bergamo A1 Stepping              |    O   |  O   |    O   |       O      |       O       |
+---------------------------------+--------+------+--------+--------------+---------------+
|Bergamo A2 Stepping              |    X   |  X   |    X   |       X      |       O       |
+---------------------------------+--------+------+--------+--------------+---------------+

================================================================================================================
                                POST CODE SEQUENCE
================================================================================================================
Warm Boot:

[TP:EA00EA01][TP:EA00E101][TP:EA00E090][TP:EA00E092][TP:EA00E091][TP:EA00E100][TP:EA00E092][TP:EA00E093]
[TP:EA00E096][TP:EA00E0B7][TP:EA00EA00][TP:EA00E0D2][TP:EA00E050][TP:EA00EA01][TP:EA00EA00][TP:EA005500]
[TP:EA00E014][TP:EA00E015][TP:EA010007][TP:EA011007][TP:EA012007][TP:EA013007][TP:EA014007][TP:EA015007]
[TP:EA016007][TP:EA017007][TP:EA018007][TP:EA019007][TP:EA01A007][TP:EA01B007][TP:EA00E050][TP:EA00EA01]
[TP:EA00EA00][TP:EA00E098][TP:EA00E099][TP:EA00EA01][TP:EA00EA00][TP:EA00E323][TP:EA00E326][TP:EA00EA01]
[TP:EA00E108][TP:EA00E0D0][TP:EA00E0C4][TP:EA00E0D3][TP:EA00E0BB][TP:EA00E0BE][TP:EA000000][TP:EA00E094]
[TP:EA00E095][TP:EA00E0B4][TP:EA00E0B7][TP:EA00EA00][TP:EA00E0C1][TP:EA00E04F][TP:EA00E0C8][TP:EA00EA01]
[TP:EA00E10D][TP:EA00E0C9][TP:EA00E10C][TP:EA00E10C][TP:EA00E103][TP:EA00E051][TP:EA00E052][TP:EA00E055]
[TP:EA00E056][TP:EA00E102][TP:EA00E0C9][TP:EA00E053][TP:EA00E054][TP:EA00E059][TP:EA00E05A][TP:EA00E057]
[TP:EA00E058][TP:EA00E0CA][TP:EA00E0C4][TP:EA00E0CD]
[00000015][00000033][00000032][0000003B][0000004F][00000060][00000061][0000009A][00000062][00000063][00000068]
[00000069][0000006A][00000070][00000090][00000091][00000092][00000093][00000094][00000093][00000094][00000093]
[00000094][00000093][00000094][00000093][00000094][00000093][00000094][00000093][00000094][00000093][00000094]
[00000093][00000094][00000093][00000094][00000093][00000094][00000093][00000094][00000093][00000094][00000093]
[00000094][00000093][00000094][00000093][00000094][00000093][00000094][00000093][00000094][00000093][00000094]
[00000093][00000094][00000093][00000094][00000093][00000094][00000093][00000094][00000093][00000094][00000093]
[00000094][00000093][00000094][00000093][00000094][00000093][00000094][00000093][00000094][00000093][00000094]
[00000095][00000096][00000092][00000092][00000092][00000092][00000092][00000092][00000092][00000099][00000091]
[00000092][00000092][00000092][00000092][00000092][00000092][00000092][00000092][00000097]

Cold Boot:

[TP:EA00E0B1][TP:EA00E098][TP:EA00E099][TP:EA00E0B7][TP:EA00EA00][TP:EA00E001][TP:EA00E00A][TP:EA00E046]
[TP:EA00EA01][TP:EA00E092][TP:EA00E093][TP:EA00E096][TP:EA00E0B7][TP:EA00EA00][TP:EA00E090][TP:EA00E092]
[TP:EA00E091][TP:EA00EA01][TP:EA00EA00][TP:EA00E0D2][TP:EA00E050][TP:EA00EA01][TP:EA00EA00][TP:EA005500]
[TP:EA00E014][TP:EA00E015][TP:EA018007][TP:EA012007][TP:EA010007][TP:EA015007][TP:EA013007][TP:EA017007]
[TP:EA016007][TP:EA019007][TP:EA011007][TP:EA014007][TP:EA01A007][TP:EA01B007][TP:EA00E014][TP:EA00E015]
[TP:EA010107][TP:EA011107][TP:EA012107][TP:EA013107][TP:EA014107][TP:EA015107][TP:EA016107][TP:EA017107]
[TP:EA018107][TP:EA019107][TP:EA01A107][TP:EA01B107][TP:EA00E33D][TP:EA00E050][TP:EA00EA01][TP:EA00EA00]
[TP:EA00E098][TP:EA00E099][TP:EA00EA01][TP:EA00EA00][TP:EA00E323][TP:EA00E326][TP:EA00EA01][TP:EA00E108]
[TP:EA00E0D0][TP:EA00E0C4][TP:EA00E0D3][TP:EA00E0BB][TP:EA00E0BE][TP:EA000000][TP:EA00E094][TP:EA00E095]
[TP:EA00E0B4][TP:EA00E0B7][TP:EA00EA00][TP:EA00E0C1][TP:EA00E04F][TP:EA00E0C8][TP:EA00EA01][TP:EA00E103]
[TP:EA00E051][TP:EA00E052][TP:EA00E055][TP:EA00E056][TP:EA00E102][TP:EA00E0C9][TP:EA00E053][TP:EA00E054]
[TP:EA00E059][TP:EA00E05A][TP:EA00E057][TP:EA00E058][TP:EA00E0CA][TP:EA00E0C4][TP:EA00E0CD]
[00000015][00000033][00000032][0000003B][0000004F][00000060][00000061][0000009A][00000062][00000063][00000068]
[00000069][0000006A][00000070][00000090][00000091][00000092][00000093][00000094][00000093][00000094][00000093]
[00000094][00000093][00000094][00000093][00000094][00000093][00000094][00000093][00000094][00000093][00000094]
[00000093][00000094][00000093][00000094][00000093][00000094][00000093][00000094][00000093][00000094][00000093]
[00000094][00000093][00000094][00000093][00000094][00000093][00000094][00000093][00000094][00000093][00000094]
[00000093][00000094][00000093][00000094][00000093][00000094][00000093][00000094][00000093][00000094][00000093]
[00000094][00000093][00000094][00000093][00000094][00000093][00000094][00000093][00000094][00000093][00000094]
[00000095][00000096][00000092][00000092][00000092][00000092][00000092][00000092][00000092][00000099][00000091]
[00000092][00000092][00000092][00000092][00000092][00000092][00000092][00000092][00000097]

>>> System Configuration:
- Power on PVT m/b with E1.S*1 + NIC Card*2
- CPU: Genoa PR(B1) 96 core * 2 (OPN:100-000000789-00)
- Memory: Samsung 96GB * 24
- BMC: v23.19.1
- OS & FBK: CentOS 8 Stream, 5.19.0-0_fbk4_zion_10711_g9cbb08e4dfe0 on an x86_64
- CPLD : 00010006

Note. 
- The sequence may change if hardware configuration is different.
- If using F0TG2A05 BIOS bring up, please power on to use with BMC v23.11.3 or later version. 

================================================================================================================
                             BIOS RECOVERY INSTRUCTIONS
================================================================================================================
- TBD. 

================================================================================================================
                             KNOWN ISSUES/WORKAROUNDS
================================================================================================================
- S4 Hibernate is not POR for Genoa.
- AHCI and NVME recovery is not functional, only USB recovery enabled, token "USB_PEI_EDKII_IOMMU_PPI_SUPPORT" should be set to "0". 
- FFS_FILE_CHECKSUM_SUPPORT is not working. 
- Boot time with GenoaPI 0080 increased comparing to previous GenoaPI 0072, memory training time a little bit reduced in 0081.
- Platform Secure Boot validated with AMI 4K/2K keys. PSB is not validated and not guaranteed to work with compressed BootBlock feature. 
  Check Porting notes how to build PSB BIOS. 

================================================================================================================
                             FEATURES ADDED/MODIFY
================================================================================================================
F0TG3A03:
- Fix PSP FW version in Type11 do not sync with PSP FW version in BIOS setup.
- Implement Boot Time PPR request SEL.
- Follow RC to recover APCB tokens after OEM IPMI boot clear CMOS.
- Modify algorithm for device's Data Link status update for DPC trigger flow to prevent DPC fail.
- Upgrade AMI label to 5.27_GenoaCrb_0ACQT021. (AGESA 1008)
- Follow AMD SN-7005 to include microcode patch for Genoa/Bergamo.
- Follow Meta BIOS requirement SPEC to add Additional PPR Info Log to SEL format.
- Fix that Slot ID and BDF of the smbios type9 didn't align with Debug runbook and lspci.
- Follow Meta BIOS Requirement SPEC to implement looping POST code when boot time PPR fail.
- Enable AMD ACT feature for checking APCB, PCD value.
- Follow AMD ADDC white paper to modify related 3 BIOS settings to support ADDC feature (aka Crashdump feature).

F0TG3A02 :
- Follow DM/SI's request to modify PCIe Initial preset hint from P8 to P6 on PVT MB.
- Remove the Location in chassis string space to meet SMBIOS spec.
- Implement looping POST code and SEL log when DIMM population error and DIMM disable condition.

F0TG3A01 :
- Follow AMD Genoa Errata to add patch to fix known issues.
  - Issue #1 - UD#/GP#/Segfault observed in SPEC06 GOBMK
  - Issue #2 – RIP corruption observed with aliased page mappings of different sizes.
- Follow customer's request to set PMIC_29 and PMIC_2A to force to DCM mode from FCCM mode.
- Correct HTTP error code to 0x63 from 0x99.
- Fix duplicated CE report when fatal/non-fatal error injected after correctable error injection
- Always update dynamic CBS options to prevent unsupported options from being listed in SCE dump.
- Implement Enable Source debug level in Release mode.
- Follow customer to Set MaxReadReq to 4096B for all root ports due to affecting NIC performance.
- Follow customer request to default enable boot time PPR.

F0TG2A08 :
Based on 2A07 add some change below:
- Fix that Slot ID and BDF of the smbios type9 didn't align with Debug runbook and Lspci.
- Fix ASPEED link speed to Gen2.

F0TG2A07 :
- Upgrade AMI label to 5.27_GenoaCrb_0ACQT020.
- Follow DM request to enable PcdMpioPostMessageSupport to let PERST# de-assertion to LTSSM detect is less than 100ms for socket 1 ports.
- Update SMBIOS type 9 for SMBIOS v3.5 definition.
- Add "OemDefaultBootOrder" to let system always boot into 09:00.0 boot drive.
- Fix SMBIOS Type9 of under SWB E1.S mapping issue.
- Based on Genoa interlock to set SMBIOS type 4 MaxSpeed to 4100.
- Re-define PCIe RAS SEL code flow.
- Set PcdMpioPostMessageSupport to false to avoid hang postcode 15 or B000A954 during AC cycle.
- Fix xGMI link speed cannot measure up on 32 GT/s.

F0TG2A06 : 
- Upgrade AMI label to 5.27_GenoaCrb_0ACQT019.
- Enable hotplug and set bus resource padding to reserve bus assignment.
- Follow customer request to disable GHES-Assist for OCP project.
- Upgrade 1006 patch to resolve S1G1 port booting time around 20min issue.
- Modified IO size to avoid re-allocate resource and reboot at postcode [95].
- Fix PcieSel failure detail for dpc condition wrong.
- Follow customer requirement spec to define Password cleared by jumper POST event to unified SEL.
- Fix SMBIOS Type9 of under SWB E1.S mapping issue.

F0TG2A05 :
- Based on BIOS common feature to set SMBIOS type 4 MaxSpeed to 4000 directly.
- Follow SI request to adjust I3C Configuration default value.
- Make _DSM Function 0x0D return to RP even if an error occurs on the DSP.
- Follow SI Std to hide some option under Advanced and Chipset page.
- Change slot threshold number for more boot device to unify boot option prefix.
- Fix system will not do endless boot loop when there is no other bootable device.
- Revert slot ID of the CPU0 P2 and P4 port to slot ID of never exchanged previous locations.
- Update root port routing table to support EDR on each RP.
- Add RISER_SLOT_NAMEING3v5_SUPPORT token to avoid some parameter wasn't referred to build error.
- Fix system will boot fail with POST code EE0000B0.
- Porting ESPI UART default to 0x2F8 from 0x3F8 for late DXE (debug mode).
- Grayout BMC Network Configuration BIOS setup page since openBMC not support.
- Set Unified ECC SEL dimm location always to 0. 
- Follow EIP#709022 to fix some module can't get correct duration in AMIPRD. 

F0TG2A04 :
- Fix incorrect severity & type in PMIC error BERT log.
- Follow the latest definition of the OEM IPMI command to send MAC with Bus/Dev/Fun of LAN port to BMC.
- Add missing memory pool free for CXL error handler.
- Implement PCIe failure event SEL.
- Follow customer's request to swap CPU0 P2/P4 BDF assignment to align with GT-T's boot drive BDF as 01:00.0.
- Filter out Broadcom switch when end device did not in use.
- Upgrade AMI label to 5.27_GenoaCrb_0ACQT018.
- Follow AGESA 1003 to update RAS message output.
- Fix replacing boot device to [Disable] when using IPMI command to set 3 unsupported devices.
- Follow customer request to modify SMBIOS Type17 BankLocator channel part to UMC number from board channel.
- Remove GenoaPI-SP5_1.0.0.3_Patch_1.
- Follow customer's request to set Determinism Control default as Power.
- Implement EDR on DSP to trigger and activate DPC control bit on downstream port by _DSM function C.
- Implement EDR on DSP to return downstream port by _DSM function D if DSP's DPC status was triggered.
- Implement EDR on DSP error handling to scan whether there is any DPC triggered by downstream port.
- Implement EDR on DSP to reassign pcie bus address from OS by _OST.
- Implement EDR on DPC to check root port AER register first when Single error received.
- Implement EDR on DPC to log event for root port.
- Implement EDR on DSP to trigger SCI and continue to complete PcieErrorLog() if Dpc Trigger Status was set.
- Add condition to show root error status if PCIe device type is RootComplex for OCP Unified SEL

F0TG2A03 :
- Implement PXE/HTTP fail SEL when no media present.
- Remove unnecessary library and rename to CBSSetupData_OCP for OCP.
- Follow Http(s) boot flow in requirement spec to change DEFAULT_MEDIA_DETECT_COUNT to 3.
- Follow GTT to modify SMBIOS type9 device name string.
- Automatically detect board type(GPIO) to load PCIe margin setting of 8 re-timer MB or 2 re-timer MB in CPM table.

F0TG2A02 :
- Fix missing string data in SMBIOS type1 when SMBIOS_TABLES_BUILD_TYPE set to 1.
- Change type2 location in chassis token name for SMBIOS_TABLES_BUILD_TYPE set to 1.
- Enable TPM SPI DI timeout support bit for OCP project to prevent the system hang without TPM device.
- Follow newsletter Genoa Weekly Updates-51-2022-12-13.pdf to add “GenoaPI-SP5_1.0.0.3_Patch_1.zip” patch.
- Modify PXE SEL error code return value.
- Implement multi board feature for using different APCB settings.
- Add "MultiBoard" module to support ABL debug mode by switching GPIO.
- Follow customer requirement to add Memory Parity error PCC 0/1 Sel log.
- Fixed multi PPR(Post Package Repair) Sel log.
- Upgrade AMI label to 5.27_GenoaCrb_0ACQT017.
- Follow DM and SI's requirement to limit P0 port's Final preset on P4 and P5.

F0TG2A01:
- Display "No Bootable Device Detected." in Quiet Boot screen.
- Implement SMBIOS type45.
- Fix build error when SMBIOS_TABLES_BUILD_TYPE set to 1.
- Enable HMAT table after AGESA 1.0.0.3 fixed hang 0x92 problem
- Fix redundant invalid boot order sel due to incorrect boot device count.
- Modify string minsize to 0 to avoid warning message when import SCE configuration.
- Follow customer's request to get certificate from BMC for HTTPS booting.
- Add TOKEN "NOT_SEPERATE_SAVED_CERT" to control if support customer certificate combination file.
- Follow BIOS requirement SPEC to set ECC Correctable error threshold default value for OCP project.

F0TG1A13:
- Upgrade AMI label to 5.27_GenoaCrb_0ACQT016.

F0TG1A12:
- Follow PCIe SPEC to check if Pcie Extended Next Capability Offset is invalid.
- Implement 500ms delay for IPMI_APP_GET_SELFTEST_RESULTS retry interval to prevent stressing BMC.
- Enable Dimm looping feature.
- Modify data type of loop counter from UNIT8 to UINT32 to avoid infinite loop.
- Follow customer's request to enable AFC for Memeye test on EVT/DVT phase.
- Remove override on Link Speed Capability when PCIe port control feature is enabled for all ports
- Modify "Server Mgmt" page and sub-page layout to standard.
- Modify behavior of input invalid IP on IPv6 address to remain previous valid IP instead of replaced by :::::::
- Follow Standard document to modify the behavior of setting IPv4 into previous address while insert invalid address.
- Correct IPv6 function and display info.
- Add CSM condition for non-CSM projects build error problem.
- Remove SATA-CDROM support in OemIpmiBoot module.
- Remove redundant UpdateSmbiosType1UUID from SmbiosUpdate OEM module.
- Fix SEL was not recorded when inject PCIe error on NIC.
- Enable EDPC control by default.
- Set DpcTriggerEnable as 2 to cover non-fatal and fatal error.
- Set AmiSetupNvLock_SUPPORT" to 0 for OCP projects
- Modify SMBIOS Type9 all devices configuration for SWB B0.
- Add Http Device to OemIpmiBootDxe.
- Follow customer's request to implement HTTP boot fail SEL.
- Modify PXESELLogInhibition module to NetworkSELLogInhibition for supporting PXE and HTTP boot fail SEL.
- Adjust CPU1 RB0's below4G to avoid rebooting when system connect with EVT/DVT SWB and GPU.
- Add E1.S boot drive.

F0TG1A11:
- Fixed that SMBIOS type 1 ProductName will discard FRU ProductInfoArea ProductPartModelNumber if it existed.
- Modify UID of UAR2 to prevent conflict in ACPI DSDT table
- Let system record SEL when PXE boot option load failed.
- Follow ERRATUM #1437 to add B0/B1 microcode to resolve "Symmetric Multi Threading System With Different CS.base Values May Behave Unpredictably" issue.
- Follow customer's request to set TDP/PPT default as 400W.
- Fix POST code is empty during system AC cycle on SOL.
- Follow customer's request to modify .rom to .BIN for OCP project.
- Fix BIOS hang at 0x9A when BMC continuously return 0x81 with FRU Read command.
- Grayout "Erase SEL" for OCP as BMC doesn't support this function.
- Implement OEM feature to preserve NIC0 PXE boot.
- Follow customer's request to disable IPV4 for OCP as default.
- Avoid CX7 NICs causing system to get stuck in the grub menu.
- Add PPR(Post Package Repair) Sel log.
- Fix boot option string length not enough in BIOS Setup fixed boot order page.
- Modify SW SSD DevPathToText to fix smbios show "in Use" if device not connect.
- Follow WW45 newsletter to add patch for GenoaPI-1002 ABL Update.

F0TG1A10:
- Make it able to control all PCIe port's speed under Setup Menu before PVT phase
- Correct the PMIC filter condition
- Implement OEM AER root error check for DPC Unified SEL.
- Enable EDR DPC event logging for OCP.
- Set condition for OEM AER root error check.
- Add PCIE device and update ASLfile for porting EDR.
- Resolved Uncorrected PCIE Error cannot be reported when EDR dpc enable.
- Follow AMD suggestion to modify MaxDxioGen to DxioGenMaxSupported.
- Follow OCP MB silkscreen to modify Frutext information.
- Follow SI Std to hide some Setup items under Advanced page
- Follow BIOS_OEM_Feature_Checklist_v0.02 to add necessary fundamental token/elink setting.
- Remove SMBIOS type 44 for OCP project.
- Enable case sensitive for SATA HDD password.
- Add Performance Measurement support for AMIPRD dump to measure POST time.
- Follow SI Std to hide some Setup items under Advanced Page:Trusted Computing/ Serial Port Console Redirection/ SIO Common Setting
- Fix bmc cannot get dimm's temperature and watts by APML due to wrong GPIO settings.
- Disable NVMe boot order group for all projects
- Upgrade AMI label to 5.27_GenoaCrb_0ACQT015.
- Implement PMIC SEL as OCP unified memory format
- Fix system will stop in DIMM looping POST code when DIMM error is not init fail.
- Implement sending flash info to bmc
- Fix BIOS POST code show error message after clear CMOS by jummper.
- Enable pciexpwakedis in PM register for WOL function
- Correct GPIO settings.
- Follow customer's request to enable AFC for Memeye test on EVT/DVT phase for F0TG.
- Disable BT/SSIF/IPMB IPMI interface.
- Modify PXE SEL definition to meet BIOS Requirement Spec 0.8. 
- Follow EE request to set BMC reset pin to correct GPIO settings.
- Make all error code to be configured to correct address.
- Fix that POST status error code will show up after set DETAILED_ERROR_MESSAGES as 0.
- Add SW SSD and GPU to SMBIOS type9 list.

F0TG1A09:
- Fix Write CRC UCE SEL not reported after F0TG_arn038_dv01, also update the SEL format.
- Fix FRU Chassis Part Number is not match SMBIOS type 3 Version issue.
- W/A for fixed boot order priorities will show more boot option if enter by user password.
- Follow SI standard SPEC and add Token to modify minimum of Setup Prompt Timeout to 1.
- Disable that always preserve the Network Stack Configuration and Boot Order.
- To implement timeout countdown based on Setup Prompt Timeout.
- Follow SI Std to hide some Setup items under Save & Exit page and Server Mgmt page.
- Follow SI Std to hide some Setup items under Boot page & Chipset page.
- Follow BMC OEM SPEC to update the code of DDR5.
- Follow AMD suggestion to limit P4/P5 root port speed to GEN3.
- Fix build error to add correct token "DEFAULT_OEM_RELEASE_SPD_CTRL".
- Fix CPU Part Number info in Type 4 is not get from CPU PN.
- Follow EIP#704393 to remove superfluous code to resolve adjusting Bottom IO issue.
- Change BMC ready pin to low active to align cpld.
- Adjust CPU1 RB1's below4G to avoid system hanging and rebooting when system connect with SWB and GPU.
- Implement OemIpmiInitAfterBmcReadyDxe driver in WaitBmcReadyDxe.
- Set TotalErrCountFor1stErrID always to 0.
- Fix BMC cannot get full BIOS version on Web UI during update.
- Force SMBIOS type 11 string 6 (2nd CPU's PPIN) to be empty if only 1 socket is installed.
- Fine-tune GPIO setting to align with CPLD.
- Follow customer request to switch IPV4 and IPV6 HTTP and PXE boot order.

F0TG1A08:
- Fix incorrect format of last boot memory error.
- Use actual channel number instead of UMC number in unified memory SEL.
- Update the coding style in OemBoardPkg\CBSSetupData\eSetupStones.xml for future convenient comparison.
- Mask PCIe UR and advisory non-fatal error.
- Implement a text item to substitute "CurrentACRecoveryMode"
- Set silicon power policy setup "Ac Loss Control" to [Always OFF] for OCP.
- Filter non-error PMIC status in OS dmesg
- Fix build error when PLATFORM_SELECT is Titanite.
- Fix ROM Size in Type 0 mismatch with actual ROM Size.
- Use token to control year of system date input range from 2000 to 2097.
- Fix HII Database size isn't enough to cause error when using AMISCE tool.
- Modified "Bmc self test log" to "BMC self test log" to align with "BMC" word of other options.
- Upgrade AMI label to 5.27_GenoaCrb_0ACQT014.
- Restore original log mechanism in OemErrorLogEventMemTest to fix abnormal SEL for DDR training error.
- Follow SI Standard to rename OS Boot device name.
- Bug fixed incorrect severity for AMD root port due to Device Status doesn't set (DXE phase).
- Clear 'Bit 6 - Capability Structure Status Valid' if PCIe capability isn't supported.
- Clear 'Bit 7 - AER Info Valid' if AER capability isn't supported.
- Correct Slot ID and IRQ number.
- Related to WaitBmcReadyDxe function Enable FRB2 in Dxe.
- Sync with Milan code to define APCB_TOKEN_UID_DF_BOTTOMIO_VALUE and BLDCFG_DF_BOTTOM_IO as MCT_BOTTOM_IO_VALUE.
- Add per project build log into veb.
- Adjust MMIO below 4G resource to resolve booting windows server led to blue screen issue as ACPI_BIOS_ERROR.
- Follow GENOA channel number to send the system info to BMC and remove the DimmChannelMap from SEL log

F0TG1A07:
- Enable "RELEASE_MODE_SYMBOL_SUPPORT" to support source level debug in release build mode.
- Add a setup item to adjust PCIe link speed of M.2 boot drive.
- Follow customer's request to enable SSC for F0TG.
- Add OEM IPMI Cmos clear function.
- Implement IPMI OEM "Set PPIN" (0x30/00,0x77).
- Implement WaitBmcReadyDxe function to OEM moudule.
- Fix NIC device SlotID not show correctly in BIOS Setup.
- Fix Boot device string size not correct.

F0TG1A06:
- Follow customer request to update SMBIOS Type17 DeviceLocator and BankLocator.
- Add Token "OEM_TYPE17_UPDATE_BANKLOCATOR" to control BankLocator format.
- Token to control PCIe port enable/disable feature.
- Change OCP NIC device SlotType to PCIe Gen4 X16.
- Get CPU0/1's PPIN by StartupThisAP of MpServices.
- Follow PCIe spec to configure Uncorrectable Error Severity.
- Upgrade AMI label to 5.27_GenoaCrb_0ACQT013.
- Update SMBIOS type1 Wakeup type for OCP.
- Follow SI standard to display "NO Security Device Found" when TPM is disabled.
- Follow SMBIOS SPEC to assign string number for SMBIOS Type 17 and fix incorrect Part number.
- Define CMOS/NVRAM configuration cleared POST event to unified SEL.
- Add supported POST Error.
- Remove redundant display message (BIOS version) on POST screen.
- Remove wait time message in InfoReport Module for OCP.
- Fix system will stop in POST long time for OCP.
- Fix DIMM is present but not trained issue.
- Fix duplicated OEM SEL for MCA error.
- Add WaitBMCReady function in DXE.
- Fix PciePortCtl function failed issue.

F0TG1A05:
- Rollback to F0TG1A03.
- Base on 1A03 to add to change the default UEFI Boot Priority sequence for F0TG.
- Base on 1A03 to add to set APML SB-TSI to I2C mode for OCP.

F0TG1A04:
- Upgrade AMI label to 5.27_GenoaCrb_0ACQT012.
- Follow OCP specification to update SMBIOS type 4/11.
- Change the default UEFI Boot Priority sequence for F0TG.
- Set APML SB-TSI to I2C mode for OCP.
- Fix build error to use token DEFAULT_OEM_APML_SBTSI_SLAVE_MODE instead of APCB_TOKEN_UID_APML_SBTSI_SLAVE_MODE_VALUE.
- Update SMBIOS type2 "Location in Chassis".
- Using "SmbiosUpdate" module to update smbios type17 DeviceLocator, BankLocator and AssetTag field.
- Follow OCP Universal DIMM table to update DIMM location format for OCP projects.
- Implement looping POST code and SEL log when DIMM init fail.
- Implement "Block SID Authentication" and "Security Freeze Lock" setup item for OCP project.
- Add POST Error A10B for TPM Selftest fail.
- Add DEBUG_GPIO to control enable/disable DebugPrint.
- Follow costomer's request to implement PXE boot fail SEL.
- Add setup item to inhibit PXE Sel log.
- Implement CPLD/Bridge IC FW version in setup main page.
- Add F0TG SMBIOS Type8 Port list.
- Add token to control OCP security freeze lock setup item.
- Add F0TG SMBIOS Type9 slot list.
- Implement OCP format PCIe/Mca/Mem error log.
- Add F0TG SMBIOS Type41 onboard device list.
- Based on customer request to update DIMM post code.
- Improve ErrDimmLoc to cover multi-socket platform.
- Remove AMD generic SMBIOS type 18/20/40.
- Fix HII Database size isn't enough when using AMISCE tool.

F0TG1A03:
- Fix system cannot boot into setup menu by serial console when adding IpmiExtended module.
- Disable time sync event from BIOS.
- Correct ManufacturerId to 0xA015 for OCP open BMC.
- Optimized the code to display FRU in setup.
- Use token OEM_PCIE_SPEED_CONTROL to set PCIe speed limit to Gen5.

F0TG1A02:
- Fix CBSSetupData module cannot be workable to enable CBS_RS_SUPPORT in OEMBOARD.sdl for OCP.
- Update new CBSgenerate.exe to support to modify AmdCbsForm.vfr and ApcbAutoGen.h.
- Add OEM module "SystemInfoToBmc".
- SMBIOS Type-1 system information "Product Name" info incorrect.
- Add Retry 2 times if FRU checksum or length is not correct.
- Update SMBIOS type 1 Product Name field to be ProductName + ProductModelNumber.
- Fix TPM cannot detect in setup menu.
- Modified SPI_CPU0_TPM_CS_N to GPIO_PU_PD_DIS as HW had already pulled up to 1.8V.
- Follow SI Std to enable Security Device Support.
- Correct Smbios Type 16 Maximum Capacity for F0TG.
- Implement an OEM module that use to clear PCIe Device, AER status and PCIe Lane Error Status Register at POST end.
- Change aspeed2600's Index port and Data port to 2E/2F.

F0TG1A01:
- Implement SMBIOS Type 0 EC version.
- Set default to DHCP IPV6 DUID-LLT by PCD for OCP.
- Implement OEM module "UpdateOEMID" to activate OA2 feature.
- Enable DEFAULT_SHOW_HIDDEN_OPTION for OCP.
- Follow OCP specification to set the default setting for [Do NOTHING] before PVT and [RESET] for PVT.
- Follow customer spec to modify setup menu string "COM0" and "COM1".
- Follow customer's spec to disable Quiet Boot for OCP.
- Follow customer's spec to set boot timeout to "7" for OCP.
- Implement "HDD Security Erase" option.
- Use token to control BMC firmware version format as {Major version}.{Minor version}.{Test version}.
- Let POST info (including error info) always show after hot key message
- Implement POST messages of F2/F11/F12 hotkey.
- Follow customer's SPEC to show CPU and Mem information in the end of post for OCP.
- Implement 'Slot # ' as prefix for UEFI NVMe boot option.
- Implement OEM_SET_POST_START_CMD in PEI and DXE phase.
- Add OEM module "FilterDuplicatedBootOption".
- Upgrade AMI label to 5.27_GenoaCrb_0ACQT011.
- update FixedBootOrder_21 to FixedBootOrder_24.
- Modify help string for setup option "Setup Prompt Timeout" default value is 7 from 5 seconds.
- Adjust "quiet boot" position after change AmiTse order to the last one in SETUP_DEFINITIONS.
- Modify "Setup Prompt Timeout" range to 1~10.
- To implement timeout countdown based on Setup Prompt Timeout.
- Modified string of NO_BOOT_OPTIONS to "No Bootable Device Detected" in POST report when system no boot device.
- Move the order of AmiBootOrder.sd behind AmiTse.sd in SETUP_DEFINITIONS for setup items in "Save & Exit" got the original order for OCP.
- Add CBSSetupData_OCP Module to control CBS setup by XML for OCP.
- Use token OEM_PSP_ERROR_INJ_SUPPORT to set [PSP error injection support] to true OCP.
- Re-add BaudRateModification module for OCP.
- Update InfoReport_06 to InfoReport_07.
- Update UefiBootOption_09 to UefiBootOption_10.
- Add "OemIpmiBoot" module.
- Add "OemBootOption" module.
- Update F0TG power on settings.

F0TG1A00:
- Initial release for power on debugging.

================================================================================================================
                             FEATURES REMOVED
================================================================================================================
F0TG3A03 :
- N/A.

F0TG3A02 :
- N/A.

F0TG3A01 :
- N/A.

F0TG2A08 : 
- N/A.

F0TG2A07 : 
- N/A.

F0TG2A06 : 
- N/A.

F0TG2A05:
- N/A.

F0TG2A04:
- N/A.

F0TG2A03:
- N/A.

F0TG2A02:
- N/A.

F0TG2A01:
- N/A.

F0TG1A13:
- N/A.

F0TG1A12:
- N/A.

F0TG1A11:
- N/A.

F0TG1A10:
- N/A.

F0TG1A09:
- N/A.

F0TG1A08:
- N/A.

F0TG1A07:
- N/A.

F0TG1A06:
- N/A.

F0TG1A05:
- N/A.

F0TG1A04:
- N/A.

F0TG1A03:
- N/A.

F0TG1A02:
- N/A.

F0TG1A01:
- N/A.

F0TG1A00:
- N/A.

================================================================================================================
                             ISSUES FIXED
================================================================================================================
F0TG3A03 :
- Etrack#427115[F0TG_PVT][PVT2 SWB][PS 7] No SEL after inject MP1 (SMU) correctable and uncorrectable error.
- Etrack#427137[F0TG_PVT][PVT2 SWB][PS 7] No SEL after inject MP5 correctable and uncorrectable error.
- Etrack#427246[F0TG_PVT][PVT2 SWB][PS 7] No OS event and SEL after injected 1st IOHUB Parity ECC Correctable Error.
- Etrack#427423[F0TG_PVT][PVT2 SWB][PS 7] No SEL when inject 1st IOHUB Parity UCP Error.
- Etrack#427425[F0TG_PVT][PVT2 SWB][PS 7] No SEL when inject 1st IOHUB Parity ECC Correctable Error.
- Etrack#427437[F0TG_PVT][PVT2 SWB][PS 7] No SEL after inject WAFL Correctable Error.
- Etrack#426989[F0TG_PVT][PVT2 SWB][PS 7] No MEMORY_ECC_ERR SEL event after inject DRAM Explicit Userspace Error UCE-fatal Error.
- Etrack#426856[F0TG_PVT][PVT2 SWB][PS 7] It lost SEL for DIMM B11 after inject DRAM Parity CE error.
- Etrack#426623[F0TG_PVT][PVT2 SWB][PS 5] The format for PSP FW version in Type11 is not sync with the one in BIOS release note
- Etrack#426530[F0TG PVT] [PS7] No SEL after injected GMI CCD correctable error on linknumber 0. (It got HW error in OS event.)
- Etrack#416765[F0TG][DVT] SMBIOS Type 7 L3 Cache size is not match to AMD SPEC.
- Etrack#427457[F0TG_PVT][PVT2 SWB][PS 7] The SEL event is wrong and no PMIC SEL after inject PMIC error.

F0TG3A02 :
- Etrack#426402[F0TG PVT] [PS5] It got Space between "Part" and "Component" in SMBIOS Type2.

F0TG3A01 :
- Etrack#424583[F0TG PVT] BIOS version in PVT should be named start from 3AXX.
- Etrack#426219[F0TG PVT] [PS5] System print ''ERROR: Bad Date/Time'' during run uefi postcode after remove/plug in Battery.
- Etrack#426133[F0TG PVT] [PS5] General Help of ''F1'' key at BIOS Setup Menu didn't show ''Tab'' Key function and not match BIOS spec defined.

F0TG2A08 :
- Etrack#427298-[F0TG_PVT][PVT2 SWB][PS 7] Slot ID and BDF of the smbios type9 didn't align with Debug runbook and Lspci.

F0TG2A07 :
- Etrack#419001[F0TG_DVT_8 Retimer][DS2] Inject WAFL Correcteable and Uncorrectable Error, SEL log ''Machine Check bank Number'' value are not meet BIOS SPEC defined.
- Etrack#418996[F0TG_DVT_8 Retimer][DS2] System reset and BMC assert uncorrectable fatal SEL after inject WAFL corrected error.
- Etrack#418789[F0TG_DVT_8 Retimer][DS2] BMC assert wrong SEL event in CPU 0 after inject MP1 Uncorrectable Error in Socket 1.
- Etrack#418509[F0TG_DVT][Hi5#2] System stuck at POST after setting ''Above 4G Decoding'' to disabled.

F0TG2A06 : 
- Etrack#420604[F0TG_DVT_8 Retimer][DS2] It still got CPU1 PN info in Type 4 after removed CPU1.
- Etrack#420145[F0TG_DVT_8 Retimer][DS1] The Link Speed of root port for PCIE device was showed N/A by using AMDXIO via PCIePortStatusSBRStress(AMDXIO).
- Etrack#419153[F0TG][DVT] Can't inject PCIe ACS Fatal Error to NIC by AMD RAS tool.
- Etrack#419099[F0TG][DVT] Can't inject PCIe Poisoned TLP TX/RX error to NIC by AMD RAS tool.

F0TG2A05:
- Etrack#418768[F0TG_DVT] BIOS setup display the ports number of PCIe SSD not match to PCIe Port Mapping.
- Etrack#408978[F0TG_EVT_PR CPU][ES4] BMC IP address (from DHCP) would not change after setting to ''Static IP address'', but it saved in BIOS successfully. (SOL did not disconnect too.)
- Etrack#418938[F0TG][DVT] POST Code not match with BIOS release note.
- Etrack#420119[F0TG_DVT_8 Retimer][DS2] DIMM info does not match between OS and SEL after inject a Fatal uncorrectable error by APEI.
- Etrack#418710[F0TG][DVT] System does not have any SEL events and dmesg when Inject PCIe fatal error (MalformedTLP,ECRC) by Keysight.
- Etrack#408863[F0TG EVT] [ES14] SEL recorded ''ECC Error Disable Threshold'' event several times on the same DRAM.
- Etrack#407589[F0TG][EVT] SUT will hang after execute ping6 command cross network segment with DHCP env in EFI shell.

F0TG2A04:
- Etrack#417050 [F0TG][DVT] SMBIOS type 9 IOX SSD that not install SSD shows Current Usage: In Use.
- Etrack#408902 [F0TG_EVT_PR CPU] SEL record wrong ''ErrID2: 0x55, ErrID1: 0x50'' error ID when inject fatal error (MalformedTLP/ECRC) on E1.S by Keysight card.

F0TG2A03:
- N/A.

F0TG2A02:
- Etrack#409843 [F0TG_EVT_PR CPU][ES6] System show memory error message on POST screen after insert bad DIMM in memory slot.

F0TG2A01:
- Etrack#409900 [F0TG_EVT_PR CPU][ES6] Type 45 is not follow definition in SMBIOS SPEC.
- Etrack#410925 [F0TG_EVT_PR CPU]AMISCE (v5.05.02.0003) pop some warning messages when import BIOS setting via SCELNX.
- Etrack#410845 [F0TG_EVT_PR CPU]SEL record POST Failure Event ''Received invalid boot order request from BMC'' after reboot OS on BIOS F0TG1A13.
- Etrack#410862 [F0TG 1A13] [ES10] It can't change boot option setting after save& reset changed boot option order. (It always keep default Boot option )
- Etrack#404675 [F0TG EVT] BIOS package is not follow rule.

F0TG1A13:
F0TG1A12:
- Etrack#409637-[F0TG_EVT_PR CPU][ES6] BMC only assert SEL for device port when inject PCIe ''LCRC-TX'' error on NIC.
- Etrack#409160-[F0TG_EVT_PR CPU] When Inject PCIe Poisoned TLP RX error to NIC1, system will reset and SEL record MACHINE_CHK_ERR event.
- Etrack#409843-[F0TG_EVT_PR CPU][ES6] System show memory error message on POST screen after insert bad DIMM in memory slot.
- Etrack#409402-[F0TG_EVT_PR CPU][2nd][B0 SWB][QS][ES2] The PCIe bus address via dmidecode was not match the bus address via lspci.
- Etrack#408978-[F0TG_EVT_PR CPU][ES4] BMC IP address (from DHCP) would not change after setting to ''Static IP address'', but it saved in BIOS successfully. (SOL did not disconnect too.)
- Etrack#408967-[F0TG_EVT_PR CPU][ES4] There are three dots in the enter field of ''Station IP Address'' can't be deleted when setting BMC static IP address in BIOS.
- Etrack#410035-[F0TG_EVT_PR CPU][ES6] Microcode version not sync with BIOS release note.
- Etrack#409892-[F0TG_EVT_PR CPU] BIOS release note ''ROM checksum'' and ''ROM MD5'' should modify to ''BIN checksum/MD5'' due to there are bin files in BIOS package.
- Etrack#404675-[F0TG EVT] BIOS package is not follow rule.
- Etrack#410567-[F0TG_EVT_PR CPU][ES6] SMBIOS type 9 PCI Slot Information Data Bus Width shouldn't be 0.

F0TG1A11:
- eTrack number - 408368-[F0TG EVT] [ES14] It is not install OS in boot drive when all 9 E1.S are inserted.
- eTrack number - 408241-[F0TG][Customer issue] POST code is empty during system AC cycle.
- eTrack number - 407228-[F0EG][EVT][BIOS 1A07] SMBIOS type 1 Product Name not follow Quanta_OCP_Genoa_BIOS_Specification_0.2 define.
- eTrack number - 408429-[F0TG][EVT] SEL not record '' POST Failure Event: System PXE boot fail'' log when PXE boot failed
- eTrack number - 408891-[F0TG_EVT_PR CPU]CPU power value will over power limit value after set CPU Power capping by BMC apml_tool then run stressapptest.
- eTrack number - 408870-[F0TG_EVT_PR CPU][ES4] BMC SEL did not rease after setting ''Erase SEL'' to ''Yes, On next reset'' in BIOS.

F0TG1A10:
- Resolved eTrack 405688-[F0TG EVT] Wake on Lan function is not available.
- Resolved eTrack 407452-[F0TG_EVT]CPU0 DIMM sensor temp and watts value display "0" on BIOS FW F0TG1A09.
- Resolved eTrack 407376-[F0TG EVT][ES2] The MB_CPU0_DIMM _PWR_W was showed 0.00 Watts via sensor-util mb with BIOS 1A09.
- Resolved eTrack 408003-[F0TG_EVT]BIOS POST code show error message after clear CMOS by jummper.
- Resolved eTrack 405883-[F0TG_EVT]BMC pop 'Unspecified error' message when get FLASH Info by ipmitool command.
- Resolved eTrack 405445-[F0TG_EVT]Upgrade info does not shows CPU socket in SMBIOS Type 4.
- Resolved eTrack 408462-[F0TG_EVT_PR CPU][ES4][BIOS F0TG1A09] The sequence of ''Designation: IOX-SSDx(PCIe x4)'' 
  does not match physical slot number actually, E1.S are installed at SSD slot1,3,5 .etc, but it shows IOX-SSD0,2,4 .etc.
- Resolved eTrack 408458-[F0TG_EVT_PR CPU][ES4][BIOS F0TG1A09] The ''type'' of ''CPUx - OCP NICx'' would show ''
  x16 PCI Express 4 x16'' in SMBIOS type 9, it should be ''x16 PCI Express 5 x16''
- Resolved eTrack 408463-[F0TG_EVT_PR CPU][ES4][BIOS F0TG1A09] All GPU can detect in OS, but they are lost in SMBIOS type 9.
- Resolved eTrack 407520-[F0TG][EVT] Please help to add ''dTPM is required and installed on MB to Power ON'' in BIOS release note.
- Resolved eTrack 407793-[F0TG][EVT] ABL version is inconsistent between BIOS setup and BIOS Release Note.

F0TG1A09:
- Resolved etrack 406476-[F0TG EVT] Part Number info in Type 4 is not get from CPU PN.
- Resolved etrack 406434-[F0TG_EVT] It was hang at post code [95] after populating the GPU into system.
- Resolved etrack 406397-[F0TG EVT] System will hang and reboot after executed command '' lspci -xxxx'' under OS.
- Resolved etrack 406023-[F0TG EVT] It shows ''./PreCheck.sh: No such file or directory'' message when execute ''./run_script'' with BIOS 1A08.
- Resolved etrack 405426-[F0TG EVT] Version info in SMBIOS Type 3 cannot meet BIOS spec V0.2 defined.
- Resolved etrack 405969-[F0TG EVT] It got 2 Boot Option #1 if enter BIOS by user password.
- Resolved etrack 405594-[F0TG] It was showed ''Error: Access forbidden, only HTTPS connection is allowed.'' durning boot post.
- Resolved etrack 406059-[F0TG EVT] Not define POST Code for each type power cycle in BIOS release note.
- Resolved etrack 407077-[F0TG EVT][ES6] The Prompt Timeout will not display during POST screen.
- Resolved etrack 406031-[F0TG EVT] POST Code cannot meet BIOS release note defined.
- Resolved etrack 405880-[F0TG_EVT] System show wrong DIMM location information when get DIMM location via IPMI command.

F0TG1A08:
- Resolved etrack 405041-[F0TG EVT] The behavior for "Year" is not follow Help text.
- Resolved etrack 405040-[F0TG EVT] It failed to dump BIOS setting by SCE tool.
- Resolved etrack 405028-[F0TG EVT] ROM Size in Type 0 mismatch with actual ROM Size.
- Resolved etrack 405003-[F0TG_EVT] The capitalization of that word "Bmc" is different from the others in BIOS setting/Server Mgmt.
- Resolved etrack 404675-[F0TG EVT] BIOS package is not follow rule.
- Resolved etrack 405880-[F0TG_EVT] System show wrong DIMM location information when get DIMM location via IPMI command.
- Resolved etrack 405701-[F0TG EVT] SMBIOS type 2 - Location In Chassis shows SLOT1.
- Resolved etrack 405557-[F0TG_EVT] The "Current Restore on AC Power Loss" setting show "Unknown" on BIOS setup menu.
- Resolved etrack 405043-[F0TG EVT] Date/Time not sync between BIOS and OS.
- Resolved etrack 404907-[F0TG_EVT] There are no POST code on SOL.
- 

F0TG1A07:
- N/A.

F0TG1A06:
- Fix DIMM is present but not trained issue.
- Fix duplicated OEM SEL for MCA error.
- Fix PciePortCtl function failed issue.

F0TG1A05:
- N/A.

F0TG1A04:
- Resolved etrack 401764- BIOS upgrade procedure is not clarify in BIOS 1A03 release note.

F0TG1A03:
- Fix PCIe speed cannot achieve to Gen5.

F0TG1A02:
- Fix TPM cannot detect in setup menu.

F0TG1A